# BASEBOARD_FAB2 (Tioga Pass) — schematic netlist excerpt (pin names and nets, part order shuffled) for the footprints in the layout excerpt that follows; sources: Cadence DE-HDL packaged netlist, KiCad conversion of Wiwynn_Tioga_Pass_MB.brd

J1F1  DM-FCI-CONN76-8R-GP-U-01  pkg CONN-G4  page 181
  PCIE_RX_DP0  = P3E_CPU1_PE3_MP_RXN<0>
  GND1  = GND
  PCIE_RX_DP6  = P3E_CPU1_PE3_MP_RXP<6>
  FAN_TACH3  = FAN_TACH3_R
  MNG_TX_DP  = NIC_MDI_MNG_TX_DP
  \pmbus_alert#\  = IRQ_SML1_PMBUS_ALERT_R_N
  PCIE_TX_DP3  = P3E_CPU1_PE3_MP_C_TXN<3>
  GND2  = GND
  PCIE_RX_DN0  = P3E_CPU1_PE3_MP_RXP<0>
  PCIE_RX_DP3  = P3E_CPU1_PE3_MP_RXN<3>
  PCIE_RX_DN6  = P3E_CPU1_PE3_MP_RXN<6>
  FAN_TACH2  = FAN_TACH2_R
  MNG_TX_DN  = NIC_MDI_MNG_TX_DN
  PMBUS_DATA  = SMB_BMC_PMBUS_STBY_LVC3_SDA
  PCIE_TX_DN3  = P3E_CPU1_PE3_MP_C_TXP<3>
  PCIE_TX_DP0  = P3E_CPU1_PE3_MP_C_TXN<0>
  GND3  = GND
  PCIE_RX_DN3  = P3E_CPU1_PE3_MP_RXP<3>
  GND4  = GND
  FAN_TACH1  = FAN_TACH1_R
  GND5  = GND
  PMBUS_CLK  = SMB_BMC_PMBUS_STBY_LVC3_SCL
  GND6  = GND
  PCIE_TX_DN0  = P3E_CPU1_PE3_MP_C_TXP<0>
  PCIE_RX_DP1  = P3E_CPU1_PE3_MP_RXN<1>
  GND7  = GND
  PCIE_RX_DP7  = P3E_CPU1_PE3_MP_RXN<7>
  FAN_TACH0  = FAN_TACH0_R
  MNG_RX_DP  = NIC_MDI_MNG_RX_DP
  GND8  = GND
  PCIE_TX_DP4  = P3E_CPU1_PE3_MP_C_TXN<4>
  GND9  = GND
  PCIE_RX_DN1  = P3E_CPU1_PE3_MP_RXP<1>
  PCIE_RX_DP4  = P3E_CPU1_PE3_MP_RXN<4>
  PCIE_RX_DN7  = P3E_CPU1_PE3_MP_RXP<7>
  \mated_in#\  = FM_MATED_IN_N
  MNG_RX_DN  = NIC_MDI_MNG_RX_DN
  PCIE_TX_DP6  = P3E_CPU1_PE3_MP_C_TXN<6>
  PCIE_TX_DN4  = P3E_CPU1_PE3_MP_C_TXP<4>
  PCIE_TX_DP1  = P3E_CPU1_PE3_MP_C_TXN<1>
  GND10  = GND
  PCIE_RX_DN4  = P3E_CPU1_PE3_MP_RXP<4>
  GND11  = GND
  FAN_PWM0  = FAN_PWM_OUT_SYS0_R1
  MB_SLOT_ID0  = FM_MB_SLOT_ID0
  PCIE_TX_DN6  = P3E_CPU1_PE3_MP_C_TXP<6>
  GND12  = GND
  PCIE_TX_DN1  = P3E_CPU1_PE3_MP_C_TXP<1>
  PCIE_RX_DP2  = P3E_CPU1_PE3_MP_RXP<2>
  GND13  = GND
  COM_TX  = SPA_MID_DBG_TX_R
  GND14  = GND
  MB_SLOT_ID1  = FM_MB_SLOT_ID1
  GND15  = GND
  PCIE_TX_DP5  = P3E_CPU1_PE3_MP_C_TXP<5>
  GND16  = GND
  PCIE_RX_DN2  = P3E_CPU1_PE3_MP_RXN<2>
  PCIE_RX_DP5  = P3E_CPU1_PE3_MP_RXP<5>
  COM_RX  = SPA_MID_DBG_RX_R
  PCIE_CLK_100M_DP  = CLK_100M_AIRMAX8_PE1_DP
  MB_SLOT_ID2  = FM_MB_SLOT_ID2
  PCIE_TX_DP7  = P3E_CPU1_PE3_MP_C_TXP<7>
  PCIE_TX_DN5  = P3E_CPU1_PE3_MP_C_TXN<5>
  PCIE_TX_DP2  = P3E_CPU1_PE3_MP_C_TXN<2>
  GND17  = GND
  PCIE_RX_DN5  = P3E_CPU1_PE3_MP_RXN<5>
  \mb_on#\  = FM_ENABLE_FAN_POWER
  PCIE_CLK_100M_DN  = CLK_100M_AIRMAX8_PE1_DN
  \pcie_perst#\  = RST_PCIE_MIDPLANE_N
  PCIE_TX_DN7  = P3E_CPU1_PE3_MP_C_TXN<7>
  GND18  = GND
  PCIE_TX_DN2  = P3E_CPU1_PE3_MP_C_TXP<2>
  J2  = GND
  J4  = GND
  J6  = GND
  J8  = GND

(kicad_pcb
	(version 20260206)
	(generator "pcbnew")
	(generator_version "10.0")
	(general
		(thickness 1.6)
		(legacy_teardrops no)
	)
	(paper "A4")
	(title_block
		(title "Wiwynn_Tioga_Pass_MB.brd")
		(comment 1 "Tioga Pass / footprint 1465 of 4770 (J1F1), pads 59-76 of 76")
	)
	(layers
		(0 "F.Cu" signal "TOP")
		(4 "In1.Cu" signal "L2GND")
		(6 "In2.Cu" signal "L3")
		(8 "In3.Cu" signal "L4GND")
		(10 "In4.Cu" signal "L5")
		(12 "In5.Cu" signal "L6GND")
		(14 "In6.Cu" signal "L7VCC")
		(16 "In7.Cu" signal "L8VCC")
		(18 "In8.Cu" signal "L9GND")
		(20 "In9.Cu" signal "L10")
		(22 "In10.Cu" signal "L11GND")
		(24 "In11.Cu" signal "L12")
		(26 "In12.Cu" signal "L13GND")
		(2 "B.Cu" signal "BOTTOM")
		(9 "F.Adhes" user "F.Adhesive")
		(11 "B.Adhes" user "B.Adhesive")
		(13 "F.Paste" user "Package Geometry/Pastemask Top")
		(15 "B.Paste" user "Package Geometry/Pastemask Bottom")
		(5 "F.SilkS" user "Ref Des/Silkscreen Top")
		(7 "B.SilkS" user "Ref Des/Silkscreen Bottom")
		(1 "F.Mask" user "Board Geometry/Soldermask Top")
		(3 "B.Mask" user "Board Geometry/Soldermask Bottom")
		(17 "Dwgs.User" user "User.Drawings")
		(19 "Cmts.User" user "User.Comments")
		(21 "Eco1.User" user "User.Eco1")
		(23 "Eco2.User" user "User.Eco2")
		(25 "Edge.Cuts" user "Board Geometry/Outline")
		(27 "Margin" user)
		(31 "F.CrtYd" user "Package Geometry/Place Bound Top")
		(29 "B.CrtYd" user "Package Geometry/Place Bound Bottom")
		(35 "F.Fab" user "Ref Des/Assembly Top")
		(33 "B.Fab" user "Ref Des/Assembly Bottom")
	)
	(footprint ""
		(layer "F.Cu")
		(at 2.29997 -32.71012 -90)
		(property "Reference" "J1F1"
			(at 0 0 270)
			(layer "F.SilkS")
			(hide yes)
			(effects
				(font
					(size 1.27 1.27)
				)
			)
		)
		(property "Value" "*"
			(at -20.8026 -3.4036 270)
			(unlocked yes)
			(layer "F.Fab")
			(hide yes)
			(effects
				(font
					(size 1.27 1.016)
					(thickness 0.1524)
				)
			)
		)
		(property "Device Type" "DM-FCI-CONN76-8R-GP-U-01_CONN-A"
			(at -20.8026 -4.9276 270)
			(unlocked yes)
			(layer "F.Fab")
			(hide yes)
			(effects
				(font
					(size 1.27 1.016)
					(thickness 0.1524)
				)
			)
		)
		(duplicate_pad_numbers_are_jumpers no)
		(pad "H3" thru_hole circle
			(at -2.999994 -3.599942 270)
			(size 0.8128 0.8128)
			(drill 0.399796)
			(layers "*.Cu" "*.Mask")
			(remove_unused_layers no)
			(net "SPA_MID_DBG_RX_R")
			(clearance 0.1524)
			(thermal_gap 0.1524)
		)
		(pad "H4" thru_hole circle
			(at -0.999998 -3.50012 270)
			(size 0.8128 0.8128)
			(drill 0.399796)
			(layers "*.Cu" "*.Mask")
			(remove_unused_layers no)
			(net "CLK_100M_AIRMAX8_PE1_DP")
			(clearance 0.2921)
			(thermal_gap 0.2921)
		)
		(pad "H5" thru_hole circle
			(at 0.999998 -3.599942 270)
			(size 0.8128 0.8128)
			(drill 0.399796)
			(layers "*.Cu" "*.Mask")
			(remove_unused_layers no)
			(net "FM_MB_SLOT_ID2")
			(clearance 0.1524)
			(thermal_gap 0.1524)
		)
		(pad "H6" thru_hole circle
			(at 2.999994 -3.50012 270)
			(size 0.8128 0.8128)
			(drill 0.399796)
			(layers "*.Cu" "*.Mask")
			(remove_unused_layers no)
			(net "P3E_CPU1_PE3_MP_C_TXP<7>")
			(clearance 0.2921)
			(thermal_gap 0.2921)
		)
		(pad "H7" thru_hole circle
			(at 4.99999 -3.599942 270)
			(size 0.8128 0.8128)
			(drill 0.399796)
			(layers "*.Cu" "*.Mask")
			(remove_unused_layers no)
			(net "P3E_CPU1_PE3_MP_C_TXN<5>")
			(clearance 0.2921)
			(thermal_gap 0.2921)
		)
		(pad "H8" thru_hole circle
			(at 6.999986 -3.50012 270)
			(size 0.8128 0.8128)
			(drill 0.399796)
			(layers "*.Cu" "*.Mask")
			(remove_unused_layers no)
			(net "P3E_CPU1_PE3_MP_C_TXN<2>")
			(clearance 0.2921)
			(thermal_gap 0.2921)
		)
		(pad "I1" thru_hole circle
			(at -6.999986 -4.99999 270)
			(size 0.8636 0.8636)
			(drill 0.499872)
			(layers "*.Cu" "*.Mask")
			(remove_unused_layers no)
			(net "GND")
			(clearance 0.1778)
			(thermal_gap 0.1778)
		)
		(pad "I2" thru_hole circle
			(at -4.99999 -4.899914 270)
			(size 0.8128 0.8128)
			(drill 0.399796)
			(layers "*.Cu" "*.Mask")
			(remove_unused_layers no)
			(net "P3E_CPU1_PE3_MP_RXN<5>")
			(clearance 0.2921)
			(thermal_gap 0.2921)
		)
		(pad "I3" thru_hole circle
			(at -2.999994 -4.99999 270)
			(size 0.8636 0.8636)
			(drill 0.499872)
			(layers "*.Cu" "*.Mask")
			(remove_unused_layers no)
			(net "FM_ENABLE_FAN_POWER")
			(clearance 0.1778)
			(thermal_gap 0.1778)
		)
		(pad "I4" thru_hole circle
			(at -0.999998 -4.899914 270)
			(size 0.8128 0.8128)
			(drill 0.399796)
			(layers "*.Cu" "*.Mask")
			(remove_unused_layers no)
			(net "CLK_100M_AIRMAX8_PE1_DN")
			(clearance 0.2921)
			(thermal_gap 0.2921)
		)
		(pad "I5" thru_hole circle
			(at 0.999998 -4.99999 270)
			(size 0.8636 0.8636)
			(drill 0.499872)
			(layers "*.Cu" "*.Mask")
			(remove_unused_layers no)
			(net "RST_PCIE_MIDPLANE_N")
			(clearance 0.1778)
			(thermal_gap 0.1778)
		)
		(pad "I6" thru_hole circle
			(at 2.999994 -4.899914 270)
			(size 0.8128 0.8128)
			(drill 0.399796)
			(layers "*.Cu" "*.Mask")
			(remove_unused_layers no)
			(net "P3E_CPU1_PE3_MP_C_TXN<7>")
			(clearance 0.2921)
			(thermal_gap 0.2921)
		)
		(pad "I7" thru_hole circle
			(at 4.99999 -4.99999 270)
			(size 0.8636 0.8636)
			(drill 0.499872)
			(layers "*.Cu" "*.Mask")
			(remove_unused_layers no)
			(net "GND")
			(clearance 0.1778)
			(thermal_gap 0.1778)
		)
		(pad "I8" thru_hole circle
			(at 6.999986 -4.899914 270)
			(size 0.8128 0.8128)
			(drill 0.399796)
			(layers "*.Cu" "*.Mask")
			(remove_unused_layers no)
			(net "P3E_CPU1_PE3_MP_C_TXP<2>")
			(clearance 0.2921)
			(thermal_gap 0.2921)
		)
		(pad "J2" thru_hole circle
			(at -4.99999 -6.299962 270)
			(size 0.8636 0.8636)
			(drill 0.499872)
			(layers "*.Cu" "*.Mask")
			(remove_unused_layers no)
			(net "GND")
			(clearance 0.1778)
			(thermal_gap 0.1778)
		)
		(pad "J4" thru_hole circle
			(at -0.999998 -6.299962 270)
			(size 0.8636 0.8636)
			(drill 0.499872)
			(layers "*.Cu" "*.Mask")
			(remove_unused_layers no)
			(net "GND")
			(clearance 0.1778)
			(thermal_gap 0.1778)
		)
		(pad "J6" thru_hole circle
			(at 2.999994 -6.299962 270)
			(size 0.8636 0.8636)
			(drill 0.499872)
			(layers "*.Cu" "*.Mask")
			(remove_unused_layers no)
			(net "GND")
			(clearance 0.1778)
			(thermal_gap 0.1778)
		)
		(pad "J8" thru_hole circle
			(at 6.999986 -6.299962 270)
			(size 0.8636 0.8636)
			(drill 0.499872)
			(layers "*.Cu" "*.Mask")
			(remove_unused_layers no)
			(net "GND")
			(clearance 0.1778)
			(thermal_gap 0.1778)
		)
	)
)
